(kicad_pcb
	(version 20260206)
	(generator "pcbnew")
	(generator_version "10.0")
	(general
		(thickness 1.6)
		(legacy_teardrops no)
	)
	(paper "A4")
	(title_block
		(title "Wiwynn_Tioga_Pass_MB.brd")
		(comment 1 "Tioga Pass / footprints 3522-3529 of 4770")
	)
	(layers
		(0 "F.Cu" signal "TOP")
		(4 "In1.Cu" signal "L2GND")
		(6 "In2.Cu" signal "L3")
		(8 "In3.Cu" signal "L4GND")
		(10 "In4.Cu" signal "L5")
		(12 "In5.Cu" signal "L6GND")
		(14 "In6.Cu" signal "L7VCC")
		(16 "In7.Cu" signal "L8VCC")
		(18 "In8.Cu" signal "L9GND")
		(20 "In9.Cu" signal "L10")
		(22 "In10.Cu" signal "L11GND")
		(24 "In11.Cu" signal "L12")
		(26 "In12.Cu" signal "L13GND")
		(2 "B.Cu" signal "BOTTOM")
		(9 "F.Adhes" user "F.Adhesive")
		(11 "B.Adhes" user "B.Adhesive")
		(13 "F.Paste" user "Package Geometry/Pastemask Top")
		(15 "B.Paste" user "Package Geometry/Pastemask Bottom")
		(5 "F.SilkS" user "Ref Des/Silkscreen Top")
		(7 "B.SilkS" user "Ref Des/Silkscreen Bottom")
		(1 "F.Mask" user "Board Geometry/Soldermask Top")
		(3 "B.Mask" user "Board Geometry/Soldermask Bottom")
		(17 "Dwgs.User" user "User.Drawings")
		(19 "Cmts.User" user "User.Comments")
		(21 "Eco1.User" user "User.Eco1")
		(23 "Eco2.User" user "User.Eco2")
		(25 "Edge.Cuts" user "Board Geometry/Outline")
		(27 "Margin" user)
		(31 "F.CrtYd" user "Package Geometry/Place Bound Top")
		(29 "B.CrtYd" user "Package Geometry/Place Bound Bottom")
		(35 "F.Fab" user "Ref Des/Assembly Top")
		(33 "B.Fab" user "Ref Des/Assembly Bottom")
	)
	(footprint ""
		(layer "B.Cu")
		(at 443.633606 -52.342034)
		(property "Reference" "C2R8"
			(at 0 0 0)
			(layer "B.SilkS")
			(hide yes)
			(effects
				(font
					(size 1.27 1.27)
				)
				(justify mirror)
			)
		)
		(property "Value" ""
			(at 0 0 0)
			(layer "B.Fab")
			(effects
				(font
					(size 1.27 1.27)
				)
				(justify mirror)
			)
		)
		(duplicate_pad_numbers_are_jumpers no)
		(fp_poly
			(pts
				(xy -0.3048 -0.1016) (xy -0.3048 0.9906) (xy 0.3048 0.9906) (xy 0.3048 -0.1016)
			)
			(stroke
				(width 0)
				(type default)
			)
			(fill no)
			(layer "B.CrtYd")
		)
		(fp_line
			(start -0.3048 -0.1016)
			(end 0.3048 -0.1016)
			(stroke
				(width 0.1)
				(type default)
			)
			(layer "B.Fab")
		)
		(fp_line
			(start -0.3048 0.9906)
			(end -0.3048 -0.1016)
			(stroke
				(width 0.1)
				(type default)
			)
			(layer "B.Fab")
		)
		(fp_line
			(start 0.3048 -0.1016)
			(end 0.3048 0.9906)
			(stroke
				(width 0.1)
				(type default)
			)
			(layer "B.Fab")
		)
		(fp_line
			(start 0.3048 0.9906)
			(end -0.3048 0.9906)
			(stroke
				(width 0.1)
				(type default)
			)
			(layer "B.Fab")
		)
		(pad "1" smd rect
			(at 0 0 180)
			(size 0.508 0.508)
			(layers "B.Cu" "B.Mask" "B.Paste")
			(net "P3E_CPU0_PE3_OCP_TXP<6>")
		)
		(pad "2" smd rect
			(at 0 0.889 180)
			(size 0.508 0.508)
			(layers "B.Cu" "B.Mask" "B.Paste")
			(net "P3E_OCP_CPU0_PE3_C_TXP<6>")
		)
		(zone
			(layer "B.Cu")
			(hatch none 0.5)
			(connect_pads
				(clearance 0)
			)
			(min_thickness 0.25)
			(keepout
				(tracks allowed)
				(vias not_allowed)
				(pads allowed)
				(copperpour not_allowed)
				(footprints allowed)
			)
			(placement
				(enabled no)
				(sheetname "")
			)
			(fill
				(thermal_gap 0.5)
				(thermal_bridge_width 0.5)
				(island_removal_mode 0)
			)
			(polygon
				(pts
					(xy 443.887606 -52.088034) (xy 443.379606 -52.088034) (xy 443.379606 -51.707034) (xy 443.887606 -51.707034)
				)
			)
		)
		(zone
			(layer "B.Cu")
			(hatch none 0.5)
			(connect_pads
				(clearance 0)
			)
			(min_thickness 0.25)
			(keepout
				(tracks not_allowed)
				(vias allowed)
				(pads allowed)
				(copperpour not_allowed)
				(footprints allowed)
			)
			(placement
				(enabled no)
				(sheetname "")
			)
			(fill
				(thermal_gap 0.5)
				(thermal_bridge_width 0.5)
				(island_removal_mode 0)
			)
			(polygon
				(pts
					(xy 443.887606 -51.707034) (xy 443.379606 -51.707034) (xy 443.379606 -52.088034) (xy 443.887606 -52.088034)
				)
			)
		)
	)
	(footprint ""
		(layer "B.Cu")
		(at 260.863334 2.123694 -90)
		(property "Reference" "SH5U1"
			(at 0 0 90)
			(layer "B.SilkS")
			(hide yes)
			(effects
				(font
					(size 1.27 1.27)
				)
				(justify mirror)
			)
		)
		(property "Value" ""
			(at 0 0 90)
			(layer "B.Fab")
			(effects
				(font
					(size 1.27 1.27)
				)
				(justify mirror)
			)
		)
		(duplicate_pad_numbers_are_jumpers no)
		(fp_poly
			(pts
				(xy 0.1651 -0.0508) (xy 0.1651 0.5842) (xy -0.1651 0.5842) (xy -0.1651 -0.0508)
			)
			(stroke
				(width 0)
				(type default)
			)
			(fill no)
			(layer "B.CrtYd")
		)
		(fp_line
			(start -0.1651 0.5842)
			(end 0.1651 0.5842)
			(stroke
				(width 0.1)
				(type default)
			)
			(layer "B.Fab")
		)
		(fp_line
			(start 0.1651 0.5842)
			(end 0.1651 -0.0508)
			(stroke
				(width 0.1)
				(type default)
			)
			(layer "B.Fab")
		)
		(fp_line
			(start -0.1651 -0.0508)
			(end -0.1651 0.5842)
			(stroke
				(width 0.1)
				(type default)
			)
			(layer "B.Fab")
		)
		(fp_line
			(start 0.1651 -0.0508)
			(end -0.1651 -0.0508)
			(stroke
				(width 0.1)
				(type default)
			)
			(layer "B.Fab")
		)
		(pad "1" smd custom
			(at 0 0 270)
			(size 0.0762 0.0762)
			(layers "B.Cu" "B.Mask" "B.Paste")
			(net "VR_PVTT_ABC_SNS")
			(options
				(clearance outline)
				(anchor circle)
			)
			(primitives
				(gr_poly
					(pts
						(arc
							(start -0.1524 0.10795)
							(mid -0.098518 0.130268)
							(end -0.0762 0.18415)
						)
						(xy -0.0762 0.22225) (xy 0.0762 0.22225)
						(arc
							(start 0.0762 0.18415)
							(mid 0.098518 0.130268)
							(end 0.1524 0.10795)
						)
						(xy 0.1524 -0.22225) (xy -0.1524 -0.22225)
					)
					(width 0)
					(fill yes)
				)
			)
		)
		(pad "2" smd custom
			(at 0 0.5334 90)
			(size 0.0762 0.0762)
			(layers "B.Cu" "B.Mask" "B.Paste")
			(net "PVTT_ABC")
			(options
				(clearance outline)
				(anchor circle)
			)
			(primitives
				(gr_poly
					(pts
						(arc
							(start -0.1524 0.10795)
							(mid -0.098518 0.130268)
							(end -0.0762 0.18415)
						)
						(xy -0.0762 0.22225) (xy 0.0762 0.22225)
						(arc
							(start 0.0762 0.18415)
							(mid 0.098518 0.130268)
							(end 0.1524 0.10795)
						)
						(xy 0.1524 -0.22225) (xy -0.1524 -0.22225)
					)
					(width 0)
					(fill yes)
				)
			)
		)
	)
	(footprint ""
		(layer "B.Cu")
		(at 371.348 -64.008 -90)
		(property "Reference" "C3P42"
			(at 0 0 90)
			(layer "B.SilkS")
			(hide yes)
			(effects
				(font
					(size 1.27 1.27)
				)
				(justify mirror)
			)
		)
		(property "Value" ""
			(at 0 0 90)
			(layer "B.Fab")
			(effects
				(font
					(size 1.27 1.27)
				)
				(justify mirror)
			)
		)
		(duplicate_pad_numbers_are_jumpers no)
		(fp_poly
			(pts
				(xy -0.3048 -0.1016) (xy -0.3048 0.9906) (xy 0.3048 0.9906) (xy 0.3048 -0.1016)
			)
			(stroke
				(width 0)
				(type default)
			)
			(fill no)
			(layer "B.CrtYd")
		)
		(fp_line
			(start -0.3048 0.9906)
			(end -0.3048 -0.1016)
			(stroke
				(width 0.1)
				(type default)
			)
			(layer "B.Fab")
		)
		(fp_line
			(start 0.3048 0.9906)
			(end -0.3048 0.9906)
			(stroke
				(width 0.1)
				(type default)
			)
			(layer "B.Fab")
		)
		(fp_line
			(start -0.3048 -0.1016)
			(end 0.3048 -0.1016)
			(stroke
				(width 0.1)
				(type default)
			)
			(layer "B.Fab")
		)
		(fp_line
			(start 0.3048 -0.1016)
			(end 0.3048 0.9906)
			(stroke
				(width 0.1)
				(type default)
			)
			(layer "B.Fab")
		)
		(pad "1" smd rect
			(at 0 0 90)
			(size 0.508 0.508)
			(layers "B.Cu" "B.Mask" "B.Paste")
			(net "P3V3_STBY")
		)
		(pad "2" smd rect
			(at 0 0.889 90)
			(size 0.508 0.508)
			(layers "B.Cu" "B.Mask" "B.Paste")
			(net "GND")
		)
		(zone
			(layer "B.Cu")
			(hatch none 0.5)
			(connect_pads
				(clearance 0)
			)
			(min_thickness 0.25)
			(keepout
				(tracks not_allowed)
				(vias allowed)
				(pads allowed)
				(copperpour not_allowed)
				(footprints allowed)
			)
			(placement
				(enabled no)
				(sheetname "")
			)
			(fill
				(thermal_gap 0.5)
				(thermal_bridge_width 0.5)
				(island_removal_mode 0)
			)
			(polygon
				(pts
					(xy 370.713 -63.754) (xy 370.713 -64.262) (xy 371.094 -64.262) (xy 371.094 -63.754)
				)
			)
		)
		(zone
			(layer "B.Cu")
			(hatch none 0.5)
			(connect_pads
				(clearance 0)
			)
			(min_thickness 0.25)
			(keepout
				(tracks allowed)
				(vias not_allowed)
				(pads allowed)
				(copperpour not_allowed)
				(footprints allowed)
			)
			(placement
				(enabled no)
				(sheetname "")
			)
			(fill
				(thermal_gap 0.5)
				(thermal_bridge_width 0.5)
				(island_removal_mode 0)
			)
			(polygon
				(pts
					(xy 371.094 -63.754) (xy 371.094 -64.262) (xy 370.713 -64.262) (xy 370.713 -63.754)
				)
			)
		)
	)
	(footprint ""
		(layer "B.Cu")
		(at 153.543 -8.128 -90)
		(property "Reference" "C7U4"
			(at 0 0 90)
			(layer "B.SilkS")
			(hide yes)
			(effects
				(font
					(size 1.27 1.27)
				)
				(justify mirror)
			)
		)
		(property "Value" ""
			(at 0 0 90)
			(layer "B.Fab")
			(effects
				(font
					(size 1.27 1.27)
				)
				(justify mirror)
			)
		)
		(duplicate_pad_numbers_are_jumpers no)
		(fp_poly
			(pts
				(xy 0.4953 -0.2032) (xy -0.4953 -0.2032) (xy -0.4953 1.6002) (xy 0.4953 1.6002)
			)
			(stroke
				(width 0)
				(type default)
			)
			(fill no)
			(layer "B.CrtYd")
		)
		(fp_line
			(start -0.4953 1.6002)
			(end 0.4953 1.6002)
			(stroke
				(width 0.1)
				(type default)
			)
			(layer "B.Fab")
		)
		(fp_line
			(start 0.4953 1.6002)
			(end 0.4953 -0.2032)
			(stroke
				(width 0.1)
				(type default)
			)
			(layer "B.Fab")
		)
		(fp_line
			(start -0.4953 -0.2032)
			(end -0.4953 1.6002)
			(stroke
				(width 0.1)
				(type default)
			)
			(layer "B.Fab")
		)
		(fp_line
			(start 0.4953 -0.2032)
			(end -0.4953 -0.2032)
			(stroke
				(width 0.1)
				(type default)
			)
			(layer "B.Fab")
		)
		(pad "1" smd rect
			(at 0 0 90)
			(size 0.762 0.889)
			(layers "B.Cu" "B.Mask" "B.Paste")
			(net "PVPP_GHJ")
		)
		(pad "2" smd rect
			(at 0 1.397 90)
			(size 0.762 0.889)
			(layers "B.Cu" "B.Mask" "B.Paste")
			(net "GND")
		)
		(zone
			(layer "B.Cu")
			(hatch none 0.5)
			(connect_pads
				(clearance 0)
			)
			(min_thickness 0.25)
			(keepout
				(tracks not_allowed)
				(vias allowed)
				(pads allowed)
				(copperpour not_allowed)
				(footprints allowed)
			)
			(placement
				(enabled no)
				(sheetname "")
			)
			(fill
				(thermal_gap 0.5)
				(thermal_bridge_width 0.5)
				(island_removal_mode 0)
			)
			(polygon
				(pts
					(xy 153.0985 -7.747) (xy 153.0985 -8.509) (xy 152.5905 -8.509) (xy 152.5905 -7.747)
				)
			)
		)
	)
	(footprint ""
		(layer "B.Cu")
		(at 32.832802 -100.613464 90)
		(property "Reference" "C9N21"
			(at 0 0 90)
			(layer "B.SilkS")
			(hide yes)
			(effects
				(font
					(size 1.27 1.27)
				)
				(justify mirror)
			)
		)
		(property "Value" ""
			(at 0 0 90)
			(layer "B.Fab")
			(effects
				(font
					(size 1.27 1.27)
				)
				(justify mirror)
			)
		)
		(duplicate_pad_numbers_are_jumpers no)
		(fp_poly
			(pts
				(xy 0.7239 -0.2159) (xy -0.7239 -0.2159) (xy -0.7239 1.9939) (xy 0.7239 1.9939)
			)
			(stroke
				(width 0)
				(type default)
			)
			(fill no)
			(layer "B.CrtYd")
		)
		(fp_line
			(start 0.7239 -0.2159)
			(end 0.7239 1.9939)
			(stroke
				(width 0.1)
				(type default)
			)
			(layer "B.Fab")
		)
		(fp_line
			(start -0.7239 -0.2159)
			(end 0.7239 -0.2159)
			(stroke
				(width 0.1)
				(type default)
			)
			(layer "B.Fab")
		)
		(fp_line
			(start 0.7239 1.9939)
			(end -0.7239 1.9939)
			(stroke
				(width 0.1)
				(type default)
			)
			(layer "B.Fab")
		)
		(fp_line
			(start -0.7239 1.9939)
			(end -0.7239 -0.2159)
			(stroke
				(width 0.1)
				(type default)
			)
			(layer "B.Fab")
		)
		(pad "1" smd rect
			(at 0 0 270)
			(size 1.27 1.016)
			(layers "B.Cu" "B.Mask" "B.Paste")
			(net "VR_FET_SW_P12V_STBY_PVCCIN_CPU1")
		)
		(pad "2" smd rect
			(at 0 1.778 270)
			(size 1.27 1.016)
			(layers "B.Cu" "B.Mask" "B.Paste")
			(net "GND")
		)
		(zone
			(layer "B.Cu")
			(hatch none 0.5)
			(connect_pads
				(clearance 0)
			)
			(min_thickness 0.25)
			(keepout
				(tracks not_allowed)
				(vias allowed)
				(pads allowed)
				(copperpour not_allowed)
				(footprints allowed)
			)
			(placement
				(enabled no)
				(sheetname "")
			)
			(fill
				(thermal_gap 0.5)
				(thermal_bridge_width 0.5)
				(island_removal_mode 0)
			)
			(polygon
				(pts
					(xy 33.340802 -101.248464) (xy 33.340802 -99.978464) (xy 34.102802 -99.978464) (xy 34.102802 -101.248464)
				)
			)
		)
	)
	(footprint ""
		(layer "B.Cu")
		(at 375.062242 -41.424352 -90)
		(property "Reference" "R2T17"
			(at 0 0 90)
			(layer "B.SilkS")
			(hide yes)
			(effects
				(font
					(size 1.27 1.27)
				)
				(justify mirror)
			)
		)
		(property "Value" ""
			(at 0 0 90)
			(layer "B.Fab")
			(effects
				(font
					(size 1.27 1.27)
				)
				(justify mirror)
			)
		)
		(duplicate_pad_numbers_are_jumpers no)
		(fp_poly
			(pts
				(xy 0.2794 -0.1016) (xy -0.2794 -0.1016) (xy -0.2794 0.9906) (xy 0.2794 0.9906)
			)
			(stroke
				(width 0)
				(type default)
			)
			(fill no)
			(layer "B.CrtYd")
		)
		(fp_line
			(start -0.2794 0.9906)
			(end -0.2794 -0.1016)
			(stroke
				(width 0.1)
				(type default)
			)
			(layer "B.Fab")
		)
		(fp_line
			(start 0.2794 0.9906)
			(end -0.2794 0.9906)
			(stroke
				(width 0.1)
				(type default)
			)
			(layer "B.Fab")
		)
		(fp_line
			(start -0.2794 -0.1016)
			(end 0.2794 -0.1016)
			(stroke
				(width 0.1)
				(type default)
			)
			(layer "B.Fab")
		)
		(fp_line
			(start 0.2794 -0.1016)
			(end 0.2794 0.9906)
			(stroke
				(width 0.1)
				(type default)
			)
			(layer "B.Fab")
		)
		(pad "1" smd rect
			(at 0 0 90)
			(size 0.508 0.508)
			(layers "B.Cu" "B.Mask" "B.Paste")
			(net "H_CPU0_ERR0_G_N")
		)
		(pad "2" smd rect
			(at 0 0.889 90)
			(size 0.508 0.508)
			(layers "B.Cu" "B.Mask" "B.Paste")
			(net "H_CPU_ERR0_GTL_R_N")
		)
		(zone
			(layer "B.Cu")
			(hatch none 0.5)
			(connect_pads
				(clearance 0)
			)
			(min_thickness 0.25)
			(keepout
				(tracks not_allowed)
				(vias allowed)
				(pads allowed)
				(copperpour not_allowed)
				(footprints allowed)
			)
			(placement
				(enabled no)
				(sheetname "")
			)
			(fill
				(thermal_gap 0.5)
				(thermal_bridge_width 0.5)
				(island_removal_mode 0)
			)
			(polygon
				(pts
					(xy 374.427242 -41.170352) (xy 374.427242 -41.678352) (xy 374.808242 -41.678352) (xy 374.808242 -41.170352)
				)
			)
		)
		(zone
			(layer "B.Cu")
			(hatch none 0.5)
			(connect_pads
				(clearance 0)
			)
			(min_thickness 0.25)
			(keepout
				(tracks allowed)
				(vias not_allowed)
				(pads allowed)
				(copperpour not_allowed)
				(footprints allowed)
			)
			(placement
				(enabled no)
				(sheetname "")
			)
			(fill
				(thermal_gap 0.5)
				(thermal_bridge_width 0.5)
				(island_removal_mode 0)
			)
			(polygon
				(pts
					(xy 374.808242 -41.170352) (xy 374.808242 -41.678352) (xy 374.427242 -41.678352) (xy 374.427242 -41.170352)
				)
			)
		)
	)
	(footprint ""
		(layer "B.Cu")
		(at 488.191302 -45.584872 -90)
		(property "Reference" "C1R16"
			(at 0 0 90)
			(layer "B.SilkS")
			(hide yes)
			(effects
				(font
					(size 1.27 1.27)
				)
				(justify mirror)
			)
		)
		(property "Value" ""
			(at 0 0 90)
			(layer "B.Fab")
			(effects
				(font
					(size 1.27 1.27)
				)
				(justify mirror)
			)
		)
		(duplicate_pad_numbers_are_jumpers no)
		(fp_poly
			(pts
				(xy 0.4953 -0.2032) (xy -0.4953 -0.2032) (xy -0.4953 1.6002) (xy 0.4953 1.6002)
			)
			(stroke
				(width 0)
				(type default)
			)
			(fill no)
			(layer "B.CrtYd")
		)
		(fp_line
			(start -0.4953 1.6002)
			(end 0.4953 1.6002)
			(stroke
				(width 0.1)
				(type default)
			)
			(layer "B.Fab")
		)
		(fp_line
			(start 0.4953 1.6002)
			(end 0.4953 -0.2032)
			(stroke
				(width 0.1)
				(type default)
			)
			(layer "B.Fab")
		)
		(fp_line
			(start -0.4953 -0.2032)
			(end -0.4953 1.6002)
			(stroke
				(width 0.1)
				(type default)
			)
			(layer "B.Fab")
		)
		(fp_line
			(start 0.4953 -0.2032)
			(end -0.4953 -0.2032)
			(stroke
				(width 0.1)
				(type default)
			)
			(layer "B.Fab")
		)
		(pad "1" smd rect
			(at 0 0 90)
			(size 0.762 0.889)
			(layers "B.Cu" "B.Mask" "B.Paste")
			(net "P0V9_LAN")
		)
		(pad "2" smd rect
			(at 0 1.397 90)
			(size 0.762 0.889)
			(layers "B.Cu" "B.Mask" "B.Paste")
			(net "GND")
		)
		(zone
			(layer "B.Cu")
			(hatch none 0.5)
			(connect_pads
				(clearance 0)
			)
			(min_thickness 0.25)
			(keepout
				(tracks not_allowed)
				(vias allowed)
				(pads allowed)
				(copperpour not_allowed)
				(footprints allowed)
			)
			(placement
				(enabled no)
				(sheetname "")
			)
			(fill
				(thermal_gap 0.5)
				(thermal_bridge_width 0.5)
				(island_removal_mode 0)
			)
			(polygon
				(pts
					(xy 487.746802 -45.203872) (xy 487.746802 -45.965872) (xy 487.238802 -45.965872) (xy 487.238802 -45.203872)
				)
			)
		)
	)
	(footprint ""
		(layer "B.Cu")
		(at 361.444794 -45.607986 -90)
		(property "Reference" "R2T71"
			(at 0 0 90)
			(layer "B.SilkS")
			(hide yes)
			(effects
				(font
					(size 1.27 1.27)
				)
				(justify mirror)
			)
		)
		(property "Value" ""
			(at 0 0 90)
			(layer "B.Fab")
			(effects
				(font
					(size 1.27 1.27)
				)
				(justify mirror)
			)
		)
		(duplicate_pad_numbers_are_jumpers no)
		(fp_poly
			(pts
				(xy 0.2794 -0.1016) (xy -0.2794 -0.1016) (xy -0.2794 0.9906) (xy 0.2794 0.9906)
			)
			(stroke
				(width 0)
				(type default)
			)
			(fill no)
			(layer "B.CrtYd")
		)
		(fp_line
			(start -0.2794 0.9906)
			(end -0.2794 -0.1016)
			(stroke
				(width 0.1)
				(type default)
			)
			(layer "B.Fab")
		)
		(fp_line
			(start 0.2794 0.9906)
			(end -0.2794 0.9906)
			(stroke
				(width 0.1)
				(type default)
			)
			(layer "B.Fab")
		)
		(fp_line
			(start -0.2794 -0.1016)
			(end 0.2794 -0.1016)
			(stroke
				(width 0.1)
				(type default)
			)
			(layer "B.Fab")
		)
		(fp_line
			(start 0.2794 -0.1016)
			(end 0.2794 0.9906)
			(stroke
				(width 0.1)
				(type default)
			)
			(layer "B.Fab")
		)
		(pad "1" smd rect
			(at 0 0 90)
			(size 0.508 0.508)
			(layers "B.Cu" "B.Mask" "B.Paste")
			(net "FM_CPU0_PROCHOT_LVT3_K_N")
		)
		(pad "2" smd rect
			(at 0 0.889 90)
			(size 0.508 0.508)
			(layers "B.Cu" "B.Mask" "B.Paste")
			(net "H_CPU0_PROCHOT_G_PCH_N")
		)
		(zone
			(layer "B.Cu")
			(hatch none 0.5)
			(connect_pads
				(clearance 0)
			)
			(min_thickness 0.25)
			(keepout
				(tracks not_allowed)
				(vias allowed)
				(pads allowed)
				(copperpour not_allowed)
				(footprints allowed)
			)
			(placement
				(enabled no)
				(sheetname "")
			)
			(fill
				(thermal_gap 0.5)
				(thermal_bridge_width 0.5)
				(island_removal_mode 0)
			)
			(polygon
				(pts
					(xy 360.809794 -45.353986) (xy 360.809794 -45.861986) (xy 361.190794 -45.861986) (xy 361.190794 -45.353986)
				)
			)
		)
		(zone
			(layer "B.Cu")
			(hatch none 0.5)
			(connect_pads
				(clearance 0)
			)
			(min_thickness 0.25)
			(keepout
				(tracks allowed)
				(vias not_allowed)
				(pads allowed)
				(copperpour not_allowed)
				(footprints allowed)
			)
			(placement
				(enabled no)
				(sheetname "")
			)
			(fill
				(thermal_gap 0.5)
				(thermal_bridge_width 0.5)
				(island_removal_mode 0)
			)
			(polygon
				(pts
					(xy 361.190794 -45.353986) (xy 361.190794 -45.861986) (xy 360.809794 -45.861986) (xy 360.809794 -45.353986)
				)
			)
		)
	)
)
